#ISCELL
  mstr_symbols cad_note *
  *
#ISCELL
  mstr_symbols design_note *
  *
#ISCELL
  mstr_symbols intel_corp_bpage *
  *
#ISCELL
  mstr_standard offpage *
  page174_i1
#ISCELL
  mstr_standard tap *
  page174_i10
#ISCELL
  mstr_standard tap *
  page174_i11
#CELL
  dev_discrete cap_a *
  page174_i12
#CELL
  dev_discrete cap_a *
  page174_i13
#CELL
  dev_discrete cap_a *
  page174_i14
#ISCELL
  mstr_symbols gnd *
  page174_i15
#ISCELL
  mstr_standard tap *
  page174_i16
#ISCELL
  mstr_standard tap *
  page174_i17
#CELL
  dev_discrete cap_a *
  page174_i18
#CELL
  dev_discrete cap_a *
  page174_i19
#ISCELL
  mstr_standard offpage *
  page174_i2
#CELL
  dev_discrete cap_a *
  page174_i20
#ISCELL
  mstr_symbols gnd *
  page174_i21
#ISCELL
  mstr_standard offpage *
  page174_i22
#ISCELL
  mstr_standard offpage *
  page174_i23
#ISCELL
  mstr_symbols p3v3 *
  page174_i24
#CELL
  mstr_discrete res *
  page174_i25
#CELL
  mstr_conn conn36_g97614001 *
  page174_i26
#ISCELL
  mstr_symbols gnd *
  page174_i27
#CELL
  dev_discrete cap_a *
  page174_i28
#CELL
  dev_discrete cap_a *
  page174_i29
#ISCELL
  mstr_standard tap *
  page174_i3
#CELL
  dev_discrete cap_a *
  page174_i30
#CELL
  dev_discrete cap_a *
  page174_i31
#CELL
  dev_discrete cap_a *
  page174_i32
#ISCELL
  mstr_standard tap *
  page174_i33
#ISCELL
  mstr_standard tap *
  page174_i34
#ISCELL
  mstr_standard tap *
  page174_i35
#ISCELL
  mstr_standard tap *
  page174_i36
#ISCELL
  mstr_standard tap *
  page174_i37
#ISCELL
  mstr_standard tap *
  page174_i38
#CELL
  dev_discrete cap_a *
  page174_i39
#ISCELL
  mstr_standard tap *
  page174_i4
#CELL
  dev_discrete cap_a *
  page174_i40
#CELL
  dev_discrete cap_a *
  page174_i41
#ISCELL
  mstr_standard tap *
  page174_i42
#ISCELL
  mstr_standard tap *
  page174_i43
#ISCELL
  mstr_standard offpage *
  page174_i44
#ISCELL
  mstr_standard offpage *
  page174_i45
#ISCELL
  mstr_standard offpage *
  page174_i46
#CELL
  mstr_discrete res *
  page174_i5
#ISCELL
  mstr_standard tap *
  page174_i6
#ISCELL
  mstr_standard tap *
  page174_i7
#CELL
  dev_discrete cap_a *
  page174_i8
#CELL
  dev_discrete cap_a *
  page174_i9
